# S9S_MB_2U (Grand Teton) — schematic netlist excerpt (pin names and nets, part order shuffled) for the footprints in the layout excerpt that follows; sources: Cadence DE-HDL packaged netlist, KiCad conversion of 03242023_DA0F0TMBIJ0_F0T_Motherboard_J_brd_V01_OCP.brd

R149  Q_RES  0 5% CHIP  pkg 0402LF  page 197 : A = PECI_PCH_R ; B = PECI_PCH_B1
PC2263  Q_CAP  22UF 16V 20% X6S  pkg C0805  page 259 : A = SW_P3V3_AUX_FLT ; B = GND
R3271  Q_RES  1K 1% EMPTY  pkg 0402LF  page 166 : A = P3V3_AUX ; B = FM_P2E_EQA1

(kicad_pcb
	(version 20260206)
	(generator "pcbnew")
	(generator_version "10.0")
	(general
		(thickness 1.6)
		(legacy_teardrops no)
	)
	(paper "A4")
	(title_block
		(title "03242023_DA0F0TMBIJ0_F0T_Motherboard_J_brd_V01_OCP.brd")
		(comment 1 "Grand Teton / footprints 2632-2634 of 6105")
	)
	(layers
		(0 "F.Cu" signal "TOP")
		(4 "In1.Cu" signal "GND")
		(6 "In2.Cu" signal "IN1")
		(8 "In3.Cu" signal "GND1")
		(10 "In4.Cu" signal "IN2")
		(12 "In5.Cu" signal "GND2")
		(14 "In6.Cu" signal "IN3")
		(16 "In7.Cu" signal "GND3")
		(18 "In8.Cu" signal "VCC")
		(20 "In9.Cu" signal "VCC1")
		(22 "In10.Cu" signal "GND4")
		(24 "In11.Cu" signal "IN4")
		(26 "In12.Cu" signal "GND5")
		(28 "In13.Cu" signal "IN5")
		(30 "In14.Cu" signal "GND6")
		(32 "In15.Cu" signal "IN6")
		(34 "In16.Cu" signal "GND7")
		(2 "B.Cu" signal "BOTTOM")
		(9 "F.Adhes" user "F.Adhesive")
		(11 "B.Adhes" user "B.Adhesive")
		(13 "F.Paste" user "Package Geometry/Pastemask Top")
		(15 "B.Paste" user "Package Geometry/Pastemask Bottom")
		(5 "F.SilkS" user "Ref Des/Silkscreen Top")
		(7 "B.SilkS" user "Ref Des/Silkscreen Bottom")
		(1 "F.Mask" user "Board Geometry/Soldermask Top")
		(3 "B.Mask" user "Board Geometry/Soldermask Bottom")
		(17 "Dwgs.User" user "User.Drawings")
		(19 "Cmts.User" user "User.Comments")
		(21 "Eco1.User" user "User.Eco1")
		(23 "Eco2.User" user "User.Eco2")
		(25 "Edge.Cuts" user "Board Geometry/Outline")
		(27 "Margin" user)
		(31 "F.CrtYd" user "Package Geometry/Place Bound Top")
		(29 "B.CrtYd" user "Package Geometry/Place Bound Bottom")
		(35 "F.Fab" user "Ref Des/Assembly Top")
		(33 "B.Fab" user "Ref Des/Assembly Bottom")
	)
	(footprint ""
		(layer "F.Cu")
		(at 460.523844 -70.271386 -90)
		(property "Reference" "PC2263"
			(at 0 0 270)
			(layer "F.SilkS")
			(hide yes)
			(effects
				(font
					(size 1.27 1.27)
				)
			)
		)
		(property "Value" ""
			(at 0 0 270)
			(layer "F.Fab")
			(effects
				(font
					(size 1.27 1.27)
				)
			)
		)
		(duplicate_pad_numbers_are_jumpers no)
		(fp_line
			(start -1.524 0.762)
			(end -1.524 -0.762)
			(stroke
				(width 0.1524)
				(type default)
			)
			(layer "F.SilkS")
		)
		(fp_line
			(start 1.524 0.762)
			(end -1.524 0.762)
			(stroke
				(width 0.1524)
				(type default)
			)
			(layer "F.SilkS")
		)
		(fp_line
			(start -1.524 -0.762)
			(end 1.524 -0.762)
			(stroke
				(width 0.1524)
				(type default)
			)
			(layer "F.SilkS")
		)
		(fp_line
			(start 1.524 -0.762)
			(end 1.524 0.762)
			(stroke
				(width 0.1524)
				(type default)
			)
			(layer "F.SilkS")
		)
		(fp_line
			(start -1.1049 0.724916)
			(end 1.1049 0.724916)
			(stroke
				(width 0.1)
				(type default)
			)
			(layer "F.Fab")
		)
		(fp_line
			(start 1.1049 0.724916)
			(end 1.1049 -0.724916)
			(stroke
				(width 0.1)
				(type default)
			)
			(layer "F.Fab")
		)
		(fp_line
			(start -1.1049 -0.724916)
			(end -1.1049 0.724916)
			(stroke
				(width 0.1)
				(type default)
			)
			(layer "F.Fab")
		)
		(fp_line
			(start 1.1049 -0.724916)
			(end -1.1049 -0.724916)
			(stroke
				(width 0.1)
				(type default)
			)
			(layer "F.Fab")
		)
		(pad "1" smd rect
			(at -0.889 0 90)
			(size 1.016 1.27)
			(layers "F.Cu" "F.Mask" "F.Paste")
			(net "SW_P3V3_AUX_FLT")
		)
		(pad "2" smd rect
			(at 0.889 0 90)
			(size 1.016 1.27)
			(layers "F.Cu" "F.Mask" "F.Paste")
			(net "GND")
		)
	)
	(footprint ""
		(layer "F.Cu")
		(at 308.00294 -56.045608 90)
		(property "Reference" "R149"
			(at 0 0 90)
			(layer "F.SilkS")
			(hide yes)
			(effects
				(font
					(size 1.27 1.27)
				)
			)
		)
		(property "Value" ""
			(at 0 0 90)
			(layer "F.Fab")
			(effects
				(font
					(size 1.27 1.27)
				)
			)
		)
		(duplicate_pad_numbers_are_jumpers no)
		(fp_line
			(start 0.7874 -0.4064)
			(end 0.7874 0.4064)
			(stroke
				(width 0.1524)
				(type default)
			)
			(layer "F.SilkS")
		)
		(fp_line
			(start -0.7874 -0.4064)
			(end 0.7874 -0.4064)
			(stroke
				(width 0.1524)
				(type default)
			)
			(layer "F.SilkS")
		)
		(fp_line
			(start 0.7874 0.4064)
			(end -0.7874 0.4064)
			(stroke
				(width 0.1524)
				(type default)
			)
			(layer "F.SilkS")
		)
		(fp_line
			(start -0.7874 0.4064)
			(end -0.7874 -0.4064)
			(stroke
				(width 0.1524)
				(type default)
			)
			(layer "F.SilkS")
		)
		(fp_line
			(start -0.12065 -0.305054)
			(end -0.12065 -0.2794)
			(stroke
				(width 0.1)
				(type default)
			)
			(layer "F.Fab")
		)
		(fp_line
			(start -0.67945 -0.305054)
			(end -0.12065 -0.305054)
			(stroke
				(width 0.1)
				(type default)
			)
			(layer "F.Fab")
		)
		(fp_line
			(start 0.67945 -0.3048)
			(end 0.67945 0.3048)
			(stroke
				(width 0.1)
				(type default)
			)
			(layer "F.Fab")
		)
		(fp_line
			(start 0.12065 -0.3048)
			(end 0.67945 -0.3048)
			(stroke
				(width 0.1)
				(type default)
			)
			(layer "F.Fab")
		)
		(fp_line
			(start 0.12065 -0.2794)
			(end 0.12065 -0.3048)
			(stroke
				(width 0.1)
				(type default)
			)
			(layer "F.Fab")
		)
		(fp_line
			(start -0.12065 -0.2794)
			(end 0.12065 -0.2794)
			(stroke
				(width 0.1)
				(type default)
			)
			(layer "F.Fab")
		)
		(fp_line
			(start 0.120396 0.2794)
			(end -0.12065 0.2794)
			(stroke
				(width 0.1)
				(type default)
			)
			(layer "F.Fab")
		)
		(fp_line
			(start -0.12065 0.2794)
			(end -0.12065 0.3048)
			(stroke
				(width 0.1)
				(type default)
			)
			(layer "F.Fab")
		)
		(fp_line
			(start 0.67945 0.3048)
			(end 0.120396 0.3048)
			(stroke
				(width 0.1)
				(type default)
			)
			(layer "F.Fab")
		)
		(fp_line
			(start 0.120396 0.3048)
			(end 0.120396 0.2794)
			(stroke
				(width 0.1)
				(type default)
			)
			(layer "F.Fab")
		)
		(fp_line
			(start -0.12065 0.3048)
			(end -0.67945 0.3048)
			(stroke
				(width 0.1)
				(type default)
			)
			(layer "F.Fab")
		)
		(fp_line
			(start -0.67945 0.3048)
			(end -0.67945 -0.305054)
			(stroke
				(width 0.1)
				(type default)
			)
			(layer "F.Fab")
		)
		(pad "1" smd circle
			(at -0.40005 0 90)
			(size 0 0)
			(layers "F.Cu" "F.Mask" "F.Paste")
			(net "PECI_PCH_R")
		)
		(pad "2" smd circle
			(at 0.40005 0 90)
			(size 0 0)
			(layers "F.Cu" "F.Mask" "F.Paste")
			(net "PECI_PCH_B1")
		)
	)
	(footprint ""
		(layer "F.Cu")
		(at 15.436596 -396.263876)
		(property "Reference" "R3271"
			(at 0 0 0)
			(layer "F.SilkS")
			(hide yes)
			(effects
				(font
					(size 1.27 1.27)
				)
			)
		)
		(property "Value" ""
			(at 0 0 0)
			(layer "F.Fab")
			(effects
				(font
					(size 1.27 1.27)
				)
			)
		)
		(duplicate_pad_numbers_are_jumpers no)
		(fp_line
			(start -0.7874 -0.4064)
			(end 0.7874 -0.4064)
			(stroke
				(width 0.1524)
				(type default)
			)
			(layer "F.SilkS")
		)
		(fp_line
			(start -0.7874 0.4064)
			(end -0.7874 -0.4064)
			(stroke
				(width 0.1524)
				(type default)
			)
			(layer "F.SilkS")
		)
		(fp_line
			(start 0.7874 -0.4064)
			(end 0.7874 0.4064)
			(stroke
				(width 0.1524)
				(type default)
			)
			(layer "F.SilkS")
		)
		(fp_line
			(start 0.7874 0.4064)
			(end -0.7874 0.4064)
			(stroke
				(width 0.1524)
				(type default)
			)
			(layer "F.SilkS")
		)
		(fp_line
			(start -0.67945 -0.305054)
			(end -0.12065 -0.305054)
			(stroke
				(width 0.1)
				(type default)
			)
			(layer "F.Fab")
		)
		(fp_line
			(start -0.67945 0.3048)
			(end -0.67945 -0.305054)
			(stroke
				(width 0.1)
				(type default)
			)
			(layer "F.Fab")
		)
		(fp_line
			(start -0.12065 -0.305054)
			(end -0.12065 -0.2794)
			(stroke
				(width 0.1)
				(type default)
			)
			(layer "F.Fab")
		)
		(fp_line
			(start -0.12065 -0.2794)
			(end 0.12065 -0.2794)
			(stroke
				(width 0.1)
				(type default)
			)
			(layer "F.Fab")
		)
		(fp_line
			(start -0.12065 0.2794)
			(end -0.12065 0.3048)
			(stroke
				(width 0.1)
				(type default)
			)
			(layer "F.Fab")
		)
		(fp_line
			(start -0.12065 0.3048)
			(end -0.67945 0.3048)
			(stroke
				(width 0.1)
				(type default)
			)
			(layer "F.Fab")
		)
		(fp_line
			(start 0.120396 0.2794)
			(end -0.12065 0.2794)
			(stroke
				(width 0.1)
				(type default)
			)
			(layer "F.Fab")
		)
		(fp_line
			(start 0.120396 0.3048)
			(end 0.120396 0.2794)
			(stroke
				(width 0.1)
				(type default)
			)
			(layer "F.Fab")
		)
		(fp_line
			(start 0.12065 -0.3048)
			(end 0.67945 -0.3048)
			(stroke
				(width 0.1)
				(type default)
			)
			(layer "F.Fab")
		)
		(fp_line
			(start 0.12065 -0.2794)
			(end 0.12065 -0.3048)
			(stroke
				(width 0.1)
				(type default)
			)
			(layer "F.Fab")
		)
		(fp_line
			(start 0.67945 -0.3048)
			(end 0.67945 0.3048)
			(stroke
				(width 0.1)
				(type default)
			)
			(layer "F.Fab")
		)
		(fp_line
			(start 0.67945 0.3048)
			(end 0.120396 0.3048)
			(stroke
				(width 0.1)
				(type default)
			)
			(layer "F.Fab")
		)
		(pad "1" smd circle
			(at -0.40005 0)
			(size 0 0)
			(layers "F.Cu" "F.Mask" "F.Paste")
			(net "P3V3_AUX")
		)
		(pad "2" smd circle
			(at 0.40005 0)
			(size 0 0)
			(layers "F.Cu" "F.Mask" "F.Paste")
			(net "FM_P2E_EQA1")
		)
	)
)
